(kicad_pcb
	(version 20260206)
	(generator "pcbnew")
	(generator_version "10.0")
	(general
		(thickness 1.6)
		(legacy_teardrops no)
	)
	(paper "A4")
	(title_block
		(title "Bryce Canyon_SCC_16316-1_OCP.brd")
		(comment 1 "Bryce Canyon / footprints 112-118 of 1561")
	)
	(layers
		(0 "F.Cu" signal "TOP")
		(4 "In1.Cu" signal "L2GND")
		(6 "In2.Cu" signal "L3")
		(8 "In3.Cu" signal "L4VCC")
		(10 "In4.Cu" signal "L5VCC")
		(12 "In5.Cu" signal "L6")
		(14 "In6.Cu" signal "L7GND")
		(2 "B.Cu" signal "BOTTOM")
		(9 "F.Adhes" user "F.Adhesive")
		(11 "B.Adhes" user "B.Adhesive")
		(13 "F.Paste" user "Package Geometry/Pastemask Top")
		(15 "B.Paste" user "Package Geometry/Pastemask Bottom")
		(5 "F.SilkS" user "Ref Des/Silkscreen Top")
		(7 "B.SilkS" user "Ref Des/Silkscreen Bottom")
		(1 "F.Mask" user "Board Geometry/Soldermask Top")
		(3 "B.Mask" user "Board Geometry/Soldermask Bottom")
		(17 "Dwgs.User" user "User.Drawings")
		(19 "Cmts.User" user "User.Comments")
		(21 "Eco1.User" user "User.Eco1")
		(23 "Eco2.User" user "User.Eco2")
		(25 "Edge.Cuts" user "Board Geometry/Outline")
		(27 "Margin" user)
		(31 "F.CrtYd" user "Package Geometry/Place Bound Top")
		(29 "B.CrtYd" user "Package Geometry/Place Bound Bottom")
		(35 "F.Fab" user "Ref Des/Assembly Top")
		(33 "B.Fab" user "Ref Des/Assembly Bottom")
	)
	(footprint ""
		(layer "F.Cu")
		(at 92.808298 -65.966086)
		(property "Reference" "R581"
			(at 0 0 0)
			(layer "F.SilkS")
			(hide yes)
			(effects
				(font
					(size 1.27 1.27)
				)
			)
		)
		(property "Value" "0R2J-2-GP"
			(at 0.064008 -3.993896 0)
			(unlocked yes)
			(layer "F.Fab")
			(hide yes)
			(effects
				(font
					(size 1.016 1.016)
					(thickness 0.1524)
				)
			)
		)
		(property "Device Type" "R402H16"
			(at 0.064008 -5.517896 0)
			(unlocked yes)
			(layer "F.Fab")
			(hide yes)
			(effects
				(font
					(size 1.016 1.016)
					(thickness 0.1524)
				)
			)
		)
		(duplicate_pad_numbers_are_jumpers no)
		(fp_line
			(start -0.508 -0.9398)
			(end -0.508 0.9398)
			(stroke
				(width 0.1524)
				(type default)
			)
			(layer "F.SilkS")
		)
		(fp_line
			(start 0.508 -0.9398)
			(end -0.508 -0.9398)
			(stroke
				(width 0.1524)
				(type default)
			)
			(layer "F.SilkS")
		)
		(fp_rect
			(start -0.508 0.9398)
			(end 0.508 -0.9398)
			(stroke
				(width 0)
				(type default)
			)
			(fill no)
			(layer "F.CrtYd")
		)
		(fp_rect
			(start -0.508 0.9398)
			(end 0.508 -0.9398)
			(stroke
				(width 0)
				(type default)
			)
			(fill no)
			(layer "F.Fab")
		)
		(pad "1" smd custom
			(at 0 -0.4445)
			(size 0.1397 0.1397)
			(layers "F.Cu" "F.Mask" "F.Paste")
			(net "GND")
			(options
				(clearance outline)
				(anchor circle)
			)
			(primitives
				(gr_poly
					(pts
						(arc
							(start -0.1778 -0.2794)
							(mid -0.249642 -0.249642)
							(end -0.2794 -0.1778)
						)
						(arc
							(start -0.2794 0.1778)
							(mid -0.249642 0.249642)
							(end -0.1778 0.2794)
						)
						(arc
							(start 0.1778 0.2794)
							(mid 0.249642 0.249642)
							(end 0.2794 0.1778)
						)
						(arc
							(start 0.2794 -0.1778)
							(mid 0.249642 -0.249642)
							(end 0.1778 -0.2794)
						)
					)
					(width 0)
					(fill yes)
				)
			)
		)
		(pad "2" smd custom
			(at 0 0.4445)
			(size 0.1397 0.1397)
			(layers "F.Cu" "F.Mask" "F.Paste")
			(net "LED46")
			(options
				(clearance outline)
				(anchor circle)
			)
			(primitives
				(gr_poly
					(pts
						(arc
							(start -0.1778 -0.2794)
							(mid -0.249642 -0.249642)
							(end -0.2794 -0.1778)
						)
						(arc
							(start -0.2794 0.1778)
							(mid -0.249642 0.249642)
							(end -0.1778 0.2794)
						)
						(arc
							(start 0.1778 0.2794)
							(mid 0.249642 0.249642)
							(end 0.2794 0.1778)
						)
						(arc
							(start 0.2794 -0.1778)
							(mid 0.249642 -0.249642)
							(end 0.1778 -0.2794)
						)
					)
					(width 0)
					(fill yes)
				)
			)
		)
	)
	(footprint ""
		(layer "F.Cu")
		(at 173.680374 -100.109782 180)
		(property "Reference" "C624"
			(at 0 0 180)
			(layer "F.SilkS")
			(hide yes)
			(effects
				(font
					(size 1.27 1.27)
				)
			)
		)
		(property "Value" "SC220P50V2KX-3GP"
			(at 1.1811 -2.7051 180)
			(unlocked yes)
			(layer "F.Fab")
			(hide yes)
			(effects
				(font
					(size 1.016 1.016)
					(thickness 0.1524)
				)
			)
		)
		(property "Device Type" "C402H22"
			(at 1.1811 -4.2291 180)
			(unlocked yes)
			(layer "F.Fab")
			(hide yes)
			(effects
				(font
					(size 1.016 1.016)
					(thickness 0.1524)
				)
			)
		)
		(duplicate_pad_numbers_are_jumpers no)
		(fp_rect
			(start -0.4318 0.9525)
			(end 0.4318 -0.9525)
			(stroke
				(width 0)
				(type default)
			)
			(fill no)
			(layer "F.CrtYd")
		)
		(fp_rect
			(start -0.4318 0.9525)
			(end 0.4318 -0.9525)
			(stroke
				(width 0)
				(type default)
			)
			(fill no)
			(layer "F.Fab")
		)
		(pad "1" smd custom
			(at 0 -0.4445 180)
			(size 0.1524 0.1524)
			(layers "F.Cu" "F.Mask" "F.Paste")
			(net "VT235_PGIN")
			(options
				(clearance outline)
				(anchor circle)
			)
			(primitives
				(gr_poly
					(pts
						(arc
							(start 0.3048 -0.2032)
							(mid 0.275042 -0.275042)
							(end 0.2032 -0.3048)
						)
						(arc
							(start -0.2032 -0.3048)
							(mid -0.275042 -0.275042)
							(end -0.3048 -0.2032)
						)
						(arc
							(start -0.3048 0.2032)
							(mid -0.275042 0.275042)
							(end -0.2032 0.3048)
						)
						(arc
							(start 0.2032 0.3048)
							(mid 0.275042 0.275042)
							(end 0.3048 0.2032)
						)
					)
					(width 0)
					(fill yes)
				)
			)
		)
		(pad "2" smd custom
			(at 0 0.4445 180)
			(size 0.1524 0.1524)
			(layers "F.Cu" "F.Mask" "F.Paste")
			(net "VT235_VREF")
			(options
				(clearance outline)
				(anchor circle)
			)
			(primitives
				(gr_poly
					(pts
						(arc
							(start 0.3048 -0.2032)
							(mid 0.275042 -0.275042)
							(end 0.2032 -0.3048)
						)
						(arc
							(start -0.2032 -0.3048)
							(mid -0.275042 -0.275042)
							(end -0.3048 -0.2032)
						)
						(arc
							(start -0.3048 0.2032)
							(mid -0.275042 0.275042)
							(end -0.2032 0.3048)
						)
						(arc
							(start 0.2032 0.3048)
							(mid 0.275042 0.275042)
							(end 0.3048 0.2032)
						)
					)
					(width 0)
					(fill yes)
				)
			)
		)
	)
	(footprint ""
		(layer "F.Cu")
		(at 87.2236 -82.2706 90)
		(property "Reference" "R549"
			(at 0 0 90)
			(layer "F.SilkS")
			(hide yes)
			(effects
				(font
					(size 1.27 1.27)
				)
			)
		)
		(property "Value" "4K7R2F-GP"
			(at 0.064008 -3.993896 90)
			(unlocked yes)
			(layer "F.Fab")
			(hide yes)
			(effects
				(font
					(size 1.016 1.016)
					(thickness 0.1524)
				)
			)
		)
		(property "Device Type" "R402H16"
			(at 0.064008 -5.517896 90)
			(unlocked yes)
			(layer "F.Fab")
			(hide yes)
			(effects
				(font
					(size 1.016 1.016)
					(thickness 0.1524)
				)
			)
		)
		(duplicate_pad_numbers_are_jumpers no)
		(fp_line
			(start 0.508 -0.9398)
			(end -0.508 -0.9398)
			(stroke
				(width 0.1524)
				(type default)
			)
			(layer "F.SilkS")
		)
		(fp_line
			(start -0.508 -0.9398)
			(end -0.508 0.9398)
			(stroke
				(width 0.1524)
				(type default)
			)
			(layer "F.SilkS")
		)
		(fp_rect
			(start -0.508 0.9398)
			(end 0.508 -0.9398)
			(stroke
				(width 0)
				(type default)
			)
			(fill no)
			(layer "F.CrtYd")
		)
		(fp_rect
			(start -0.508 0.9398)
			(end 0.508 -0.9398)
			(stroke
				(width 0)
				(type default)
			)
			(fill no)
			(layer "F.Fab")
		)
		(pad "1" smd custom
			(at 0 -0.4445 90)
			(size 0.1397 0.1397)
			(layers "F.Cu" "F.Mask" "F.Paste")
			(net "P0V9_PG")
			(options
				(clearance outline)
				(anchor circle)
			)
			(primitives
				(gr_poly
					(pts
						(arc
							(start -0.1778 -0.2794)
							(mid -0.249642 -0.249642)
							(end -0.2794 -0.1778)
						)
						(arc
							(start -0.2794 0.1778)
							(mid -0.249642 0.249642)
							(end -0.1778 0.2794)
						)
						(arc
							(start 0.1778 0.2794)
							(mid 0.249642 0.249642)
							(end 0.2794 0.1778)
						)
						(arc
							(start 0.2794 -0.1778)
							(mid 0.249642 -0.249642)
							(end 0.1778 -0.2794)
						)
					)
					(width 0)
					(fill yes)
				)
			)
		)
		(pad "2" smd custom
			(at 0 0.4445 90)
			(size 0.1397 0.1397)
			(layers "F.Cu" "F.Mask" "F.Paste")
			(net "GND")
			(options
				(clearance outline)
				(anchor circle)
			)
			(primitives
				(gr_poly
					(pts
						(arc
							(start -0.1778 -0.2794)
							(mid -0.249642 -0.249642)
							(end -0.2794 -0.1778)
						)
						(arc
							(start -0.2794 0.1778)
							(mid -0.249642 0.249642)
							(end -0.1778 0.2794)
						)
						(arc
							(start 0.1778 0.2794)
							(mid 0.249642 0.249642)
							(end 0.2794 0.1778)
						)
						(arc
							(start 0.2794 -0.1778)
							(mid 0.249642 -0.249642)
							(end 0.1778 -0.2794)
						)
					)
					(width 0)
					(fill yes)
				)
			)
		)
	)
	(footprint ""
		(layer "F.Cu")
		(at 163.290504 -9.237472 180)
		(property "Reference" "U12"
			(at 0 0 180)
			(layer "F.SilkS")
			(hide yes)
			(effects
				(font
					(size 1.27 1.27)
				)
			)
		)
		(property "Value" "SNLVC8T245DGVR-GP"
			(at 0 -11.1252 180)
			(unlocked yes)
			(layer "F.Fab")
			(hide yes)
			(effects
				(font
					(size 1.016 1.016)
					(thickness 0.1524)
				)
			)
		)
		(property "Device Type" "TVSOP24H48"
			(at 0 -12.6492 180)
			(unlocked yes)
			(layer "F.Fab")
			(hide yes)
			(effects
				(font
					(size 1.016 1.016)
					(thickness 0.1524)
				)
			)
		)
		(duplicate_pad_numbers_are_jumpers no)
		(fp_line
			(start 2.2987 1.397)
			(end 2.2987 -1.397)
			(stroke
				(width 0.1524)
				(type default)
			)
			(layer "F.SilkS")
		)
		(fp_line
			(start 2.2987 -1.397)
			(end -2.9337 -1.397)
			(stroke
				(width 0.1524)
				(type default)
			)
			(layer "F.SilkS")
		)
		(fp_line
			(start -2.5654 0)
			(end -2.9337 0.3683)
			(stroke
				(width 0.1524)
				(type default)
			)
			(layer "F.SilkS")
		)
		(fp_line
			(start -2.7559 1.397)
			(end -2.7559 3.8354)
			(stroke
				(width 0.508)
				(type default)
			)
			(layer "F.SilkS")
		)
		(fp_line
			(start -2.9337 1.397)
			(end 2.2987 1.397)
			(stroke
				(width 0.1524)
				(type default)
			)
			(layer "F.SilkS")
		)
		(fp_line
			(start -2.9337 -0.3683)
			(end -2.5654 0)
			(stroke
				(width 0.1524)
				(type default)
			)
			(layer "F.SilkS")
		)
		(fp_line
			(start -2.9337 -1.397)
			(end -2.9337 1.397)
			(stroke
				(width 0.1524)
				(type default)
			)
			(layer "F.SilkS")
		)
		(fp_rect
			(start -3.0099 4.0894)
			(end 3.0099 -4.0894)
			(stroke
				(width 0)
				(type default)
			)
			(fill no)
			(layer "F.CrtYd")
		)
		(fp_poly
			(pts
				(xy -3.0099 -4.0894) (xy 3.0099 -4.0894) (xy 3.0099 4.0894) (xy -3.0099 4.0894)
			)
			(stroke
				(width 0)
				(type default)
			)
			(fill no)
			(layer "F.Fab")
		)
		(pad "1" smd rect
			(at -2.19964 2.8194 180)
			(size 0.2032 1.524)
			(layers "F.Cu" "F.Mask" "F.Paste")
			(net "P3V3")
		)
		(pad "2" smd rect
			(at -1.79959 2.8194 180)
			(size 0.2032 1.524)
			(layers "F.Cu" "F.Mask" "F.Paste")
			(net "P3V3")
		)
		(pad "3" smd rect
			(at -1.39954 2.8194 180)
			(size 0.2032 1.524)
			(layers "F.Cu" "F.Mask" "F.Paste")
			(net "BMC_LOC_HEARTBEAT")
		)
		(pad "4" smd rect
			(at -0.99949 2.8194 180)
			(size 0.2032 1.524)
			(layers "F.Cu" "F.Mask" "F.Paste")
			(net "BMC_RMT_HEARTBEAT")
		)
		(pad "5" smd rect
			(at -0.59944 2.8194 180)
			(size 0.2032 1.524)
			(layers "F.Cu" "F.Mask" "F.Paste")
			(net "SCC_RESET_BUF_N")
		)
		(pad "6" smd rect
			(at -0.19939 2.8194 180)
			(size 0.2032 1.524)
			(layers "F.Cu" "F.Mask" "F.Paste")
			(net "SCC_RMT_HEARTBEAT")
		)
		(pad "7" smd rect
			(at 0.19939 2.8194 180)
			(size 0.2032 1.524)
			(layers "F.Cu" "F.Mask" "F.Paste")
			(net "DRIVE_INSERT_ALERT_N")
		)
		(pad "8" smd rect
			(at 0.59944 2.8194 180)
			(size 0.2032 1.524)
			(layers "F.Cu" "F.Mask" "F.Paste")
			(net "COMP_SPARE_0")
		)
		(pad "9" smd rect
			(at 0.99949 2.8194 180)
			(size 0.2032 1.524)
			(layers "F.Cu" "F.Mask" "F.Paste")
			(net "Net_20")
		)
		(pad "10" smd rect
			(at 1.39954 2.8194 180)
			(size 0.2032 1.524)
			(layers "F.Cu" "F.Mask" "F.Paste")
			(net "BMC_SPARE_0")
		)
		(pad "11" smd rect
			(at 1.79959 2.8194 180)
			(size 0.2032 1.524)
			(layers "F.Cu" "F.Mask" "F.Paste")
			(net "GND")
		)
		(pad "12" smd rect
			(at 2.19964 2.8194 180)
			(size 0.2032 1.524)
			(layers "F.Cu" "F.Mask" "F.Paste")
			(net "GND")
		)
		(pad "13" smd rect
			(at 2.19964 -2.8194 180)
			(size 0.2032 1.524)
			(layers "F.Cu" "F.Mask" "F.Paste")
			(net "GND")
		)
		(pad "14" smd rect
			(at 1.79959 -2.8194 180)
			(size 0.2032 1.524)
			(layers "F.Cu" "F.Mask" "F.Paste")
			(net "BMC_SPARE_0_LS")
		)
		(pad "15" smd rect
			(at 1.39954 -2.8194 180)
			(size 0.2032 1.524)
			(layers "F.Cu" "F.Mask" "F.Paste")
			(net "Net_21")
		)
		(pad "16" smd rect
			(at 0.99949 -2.8194 180)
			(size 0.2032 1.524)
			(layers "F.Cu" "F.Mask" "F.Paste")
			(net "COMP_SPARE_0_LS")
		)
		(pad "17" smd rect
			(at 0.59944 -2.8194 180)
			(size 0.2032 1.524)
			(layers "F.Cu" "F.Mask" "F.Paste")
			(net "DRIVE_INSERT_ALERT_LS_N")
		)
		(pad "18" smd rect
			(at 0.19939 -2.8194 180)
			(size 0.2032 1.524)
			(layers "F.Cu" "F.Mask" "F.Paste")
			(net "SCC_RMT_HEARTBEAT_LS")
		)
		(pad "19" smd rect
			(at -0.19939 -2.8194 180)
			(size 0.2032 1.524)
			(layers "F.Cu" "F.Mask" "F.Paste")
			(net "SCC_RESET_LS_N")
		)
		(pad "20" smd rect
			(at -0.59944 -2.8194 180)
			(size 0.2032 1.524)
			(layers "F.Cu" "F.Mask" "F.Paste")
			(net "BMC_RMT_HEARTBEAT_LS")
		)
		(pad "21" smd rect
			(at -0.99949 -2.8194 180)
			(size 0.2032 1.524)
			(layers "F.Cu" "F.Mask" "F.Paste")
			(net "BMC_LOC_HEARTBEAT_LS")
		)
		(pad "22" smd rect
			(at -1.39954 -2.8194 180)
			(size 0.2032 1.524)
			(layers "F.Cu" "F.Mask" "F.Paste")
			(net "LS_EN_U12")
		)
		(pad "23" smd rect
			(at -1.79959 -2.8194 180)
			(size 0.2032 1.524)
			(layers "F.Cu" "F.Mask" "F.Paste")
			(net "P1V8_E")
		)
		(pad "24" smd rect
			(at -2.19964 -2.8194 180)
			(size 0.2032 1.524)
			(layers "F.Cu" "F.Mask" "F.Paste")
			(net "P1V8_E")
		)
	)
	(footprint ""
		(layer "F.Cu")
		(at 179.578 -55.245 90)
		(property "Reference" "TP114"
			(at 0 0 90)
			(layer "F.SilkS")
			(hide yes)
			(effects
				(font
					(size 1.27 1.27)
				)
			)
		)
		(property "Value" "TPAD28-2-GP"
			(at -0.0127 -1.6637 90)
			(unlocked yes)
			(layer "F.Fab")
			(hide yes)
			(effects
				(font
					(size 1.016 1.016)
					(thickness 0.1524)
				)
			)
		)
		(property "Device Type" "TPAD28"
			(at -0.0127 -3.1877 90)
			(unlocked yes)
			(layer "F.Fab")
			(hide yes)
			(effects
				(font
					(size 1.016 1.016)
					(thickness 0.1524)
				)
			)
		)
		(duplicate_pad_numbers_are_jumpers no)
		(fp_poly
			(pts
				(arc
					(start 0 0.3556)
					(mid 0 -0.3556)
					(end 0 0.3556)
				)
			)
			(stroke
				(width 0)
				(type default)
			)
			(fill no)
			(layer "F.CrtYd")
		)
		(fp_poly
			(pts
				(arc
					(start 0 0.6096)
					(mid 0 -0.6096)
					(end 0 0.6096)
				)
			)
			(stroke
				(width 0)
				(type default)
			)
			(fill no)
			(layer "F.Fab")
		)
		(pad "1" smd circle
			(at 0 0 90)
			(size 0.7112 0.7112)
			(layers "F.Cu" "F.Mask" "F.Paste")
			(net "XM_RB")
		)
	)
	(footprint ""
		(layer "F.Cu")
		(at 70.612 -51.943 90)
		(property "Reference" "R163"
			(at 0 0 90)
			(layer "F.SilkS")
			(hide yes)
			(effects
				(font
					(size 1.27 1.27)
				)
			)
		)
		(property "Value" "D51R3F-2-GP"
			(at -0.0254 -2.5146 90)
			(unlocked yes)
			(layer "F.Fab")
			(hide yes)
			(effects
				(font
					(size 1.016 1.016)
					(thickness 0.1524)
				)
			)
		)
		(property "Device Type" "R603H22"
			(at -0.0254 -4.0386 90)
			(unlocked yes)
			(layer "F.Fab")
			(hide yes)
			(effects
				(font
					(size 1.016 1.016)
					(thickness 0.1524)
				)
			)
		)
		(duplicate_pad_numbers_are_jumpers no)
		(fp_line
			(start 0.2032 0)
			(end 0.4826 0)
			(stroke
				(width 0.2032)
				(type default)
			)
			(layer "F.SilkS")
		)
		(fp_line
			(start -0.4826 0)
			(end -0.2032 0)
			(stroke
				(width 0.2032)
				(type default)
			)
			(layer "F.SilkS")
		)
		(fp_rect
			(start -0.5842 1.3335)
			(end 0.5842 -1.3335)
			(stroke
				(width 0)
				(type default)
			)
			(fill no)
			(layer "F.CrtYd")
		)
		(fp_rect
			(start -0.5842 1.3335)
			(end 0.5842 -1.3335)
			(stroke
				(width 0)
				(type default)
			)
			(fill no)
			(layer "F.Fab")
		)
		(pad "1" smd custom
			(at 0 -0.762 90)
			(size 0.2159 0.2159)
			(layers "F.Cu" "F.Mask" "F.Paste")
			(net "P0V9")
			(options
				(clearance outline)
				(anchor circle)
			)
			(primitives
				(gr_poly
					(pts
						(arc
							(start -0.3302 -0.4318)
							(mid -0.402042 -0.402042)
							(end -0.4318 -0.3302)
						)
						(arc
							(start -0.4318 0.3302)
							(mid -0.402042 0.402042)
							(end -0.3302 0.4318)
						)
						(arc
							(start 0.3302 0.4318)
							(mid 0.402042 0.402042)
							(end 0.4318 0.3302)
						)
						(arc
							(start 0.4318 -0.3302)
							(mid 0.402042 -0.402042)
							(end 0.3302 -0.4318)
						)
					)
					(width 0)
					(fill yes)
				)
			)
		)
		(pad "2" smd custom
			(at 0 0.762 90)
			(size 0.2159 0.2159)
			(layers "F.Cu" "F.Mask" "F.Paste")
			(net "GB_VDDA")
			(options
				(clearance outline)
				(anchor circle)
			)
			(primitives
				(gr_poly
					(pts
						(arc
							(start -0.3302 -0.4318)
							(mid -0.402042 -0.402042)
							(end -0.4318 -0.3302)
						)
						(arc
							(start -0.4318 0.3302)
							(mid -0.402042 0.402042)
							(end -0.3302 0.4318)
						)
						(arc
							(start 0.3302 0.4318)
							(mid 0.402042 0.402042)
							(end 0.4318 0.3302)
						)
						(arc
							(start 0.4318 -0.3302)
							(mid 0.402042 -0.402042)
							(end 0.3302 -0.4318)
						)
					)
					(width 0)
					(fill yes)
				)
			)
		)
	)
	(footprint ""
		(layer "F.Cu")
		(at 140.514324 -104.872028 180)
		(property "Reference" "R382"
			(at 0 0 180)
			(layer "F.SilkS")
			(hide yes)
			(effects
				(font
					(size 1.27 1.27)
				)
			)
		)
		(property "Value" "0R5J-5-GP"
			(at 0 -8.9535 180)
			(unlocked yes)
			(layer "F.Fab")
			(hide yes)
			(effects
				(font
					(size 1.27 1.016)
					(thickness 0.1524)
				)
			)
		)
		(property "Device Type" "R805H24"
			(at 0 -10.6299 180)
			(unlocked yes)
			(layer "F.Fab")
			(hide yes)
			(effects
				(font
					(size 1.27 1.016)
					(thickness 0.1524)
				)
			)
		)
		(duplicate_pad_numbers_are_jumpers no)
		(fp_line
			(start 0.889 1.7018)
			(end 0.889 -0.508)
			(stroke
				(width 0.1524)
				(type default)
			)
			(layer "F.SilkS")
		)
		(fp_line
			(start 0.889 -1.7018)
			(end 0.889 -0.381)
			(stroke
				(width 0.1524)
				(type default)
			)
			(layer "F.SilkS")
		)
		(fp_line
			(start 0.889 -1.7018)
			(end -0.889 -1.7018)
			(stroke
				(width 0.1524)
				(type default)
			)
			(layer "F.SilkS")
		)
		(fp_line
			(start -0.889 1.7018)
			(end 0.889 1.7018)
			(stroke
				(width 0.1524)
				(type default)
			)
			(layer "F.SilkS")
		)
		(fp_line
			(start -0.889 0.0762)
			(end -0.889 1.7018)
			(stroke
				(width 0.1524)
				(type default)
			)
			(layer "F.SilkS")
		)
		(fp_line
			(start -0.889 -1.7018)
			(end -0.889 0.2794)
			(stroke
				(width 0.1524)
				(type default)
			)
			(layer "F.SilkS")
		)
		(fp_poly
			(pts
				(xy 0.9652 -1.778) (xy 0.9652 1.778) (xy -0.9652 1.778) (xy -0.9652 -1.778)
			)
			(stroke
				(width 0)
				(type default)
			)
			(fill no)
			(layer "F.CrtYd")
		)
		(fp_rect
			(start -0.9652 1.778)
			(end 0.9652 -1.778)
			(stroke
				(width 0)
				(type default)
			)
			(fill no)
			(layer "F.Fab")
		)
		(pad "1" smd rect
			(at 0 -0.9652 180)
			(size 1.397 1.143)
			(layers "F.Cu" "F.Mask" "F.Paste")
			(net "P1V5_E")
		)
		(pad "2" smd rect
			(at 0 0.9652 180)
			(size 1.397 1.143)
			(layers "F.Cu" "F.Mask" "F.Paste")
			(net "P1V5_E_OUT")
		)
	)
)
